(kicad_pcb
	(version 20260206)
	(generator "pcbnew")
	(generator_version "10.0")
	(general
		(thickness 1.6)
		(legacy_teardrops no)
	)
	(paper "A4")
	(title_block
		(title "baseboard — 13948-1b.1110WZS1818.brd")
		(comment 1 "Honey Badger (Wiwynn) / footprints 2319-2325 of 2523")
	)
	(layers
		(0 "F.Cu" signal "TOP")
		(4 "In1.Cu" signal "L2GND")
		(6 "In2.Cu" signal "L3")
		(8 "In3.Cu" signal "L4VCC")
		(10 "In4.Cu" signal "L5VCC")
		(12 "In5.Cu" signal "L6")
		(14 "In6.Cu" signal "L7GND")
		(2 "B.Cu" signal "BOTTOM")
		(9 "F.Adhes" user "F.Adhesive")
		(11 "B.Adhes" user "B.Adhesive")
		(13 "F.Paste" user "Package Geometry/Pastemask Top")
		(15 "B.Paste" user "Package Geometry/Pastemask Bottom")
		(5 "F.SilkS" user "Ref Des/Silkscreen Top")
		(7 "B.SilkS" user "Ref Des/Silkscreen Bottom")
		(1 "F.Mask" user "Board Geometry/Soldermask Top")
		(3 "B.Mask" user "Board Geometry/Soldermask Bottom")
		(17 "Dwgs.User" user "User.Drawings")
		(19 "Cmts.User" user "User.Comments")
		(21 "Eco1.User" user "User.Eco1")
		(23 "Eco2.User" user "User.Eco2")
		(25 "Edge.Cuts" user "Board Geometry/Outline")
		(27 "Margin" user)
		(31 "F.CrtYd" user "Package Geometry/Place Bound Top")
		(29 "B.CrtYd" user "Package Geometry/Place Bound Bottom")
		(35 "F.Fab" user "Ref Des/Assembly Top")
		(33 "B.Fab" user "Ref Des/Assembly Bottom")
	)
	(footprint ""
		(layer "B.Cu")
		(at 11.938 -220.599 90)
		(property "Reference" "SR316"
			(at 0 0 90)
			(layer "B.SilkS")
			(hide yes)
			(effects
				(font
					(size 1.27 1.27)
				)
				(justify mirror)
			)
		)
		(property "Value" "0R2J-2-GP"
			(at -0.064008 -3.993896 90)
			(unlocked yes)
			(layer "B.Fab")
			(hide yes)
			(effects
				(font
					(size 1.016 1.016)
					(thickness 0.1524)
				)
				(justify mirror)
			)
		)
		(property "Device Type" "R402H16"
			(at -0.064008 -5.517896 90)
			(unlocked yes)
			(layer "B.Fab")
			(hide yes)
			(effects
				(font
					(size 1.016 1.016)
					(thickness 0.1524)
				)
				(justify mirror)
			)
		)
		(duplicate_pad_numbers_are_jumpers no)
		(fp_line
			(start 0.508 -0.9398)
			(end 0.508 0.9398)
			(stroke
				(width 0.1524)
				(type default)
			)
			(layer "B.SilkS")
		)
		(fp_line
			(start -0.508 -0.9398)
			(end 0.508 -0.9398)
			(stroke
				(width 0.1524)
				(type default)
			)
			(layer "B.SilkS")
		)
		(fp_rect
			(start 0.508 0.9398)
			(end -0.508 -0.9398)
			(stroke
				(width 0)
				(type default)
			)
			(fill no)
			(layer "B.CrtYd")
		)
		(fp_rect
			(start 0.508 0.9398)
			(end -0.508 -0.9398)
			(stroke
				(width 0)
				(type default)
			)
			(fill no)
			(layer "B.Fab")
		)
		(pad "1" smd custom
			(at 0 -0.4445 270)
			(size 0.1397 0.1397)
			(layers "B.Cu" "B.Mask" "B.Paste")
			(net "EXP_SDA_0")
			(options
				(clearance outline)
				(anchor circle)
			)
			(primitives
				(gr_poly
					(pts
						(arc
							(start -0.1778 0.2794)
							(mid -0.249642 0.249642)
							(end -0.2794 0.1778)
						)
						(arc
							(start -0.2794 -0.1778)
							(mid -0.249642 -0.249642)
							(end -0.1778 -0.2794)
						)
						(arc
							(start 0.1778 -0.2794)
							(mid 0.249642 -0.249642)
							(end 0.2794 -0.1778)
						)
						(arc
							(start 0.2794 0.1778)
							(mid 0.249642 0.249642)
							(end 0.1778 0.2794)
						)
					)
					(width 0)
					(fill yes)
				)
			)
		)
		(pad "2" smd custom
			(at 0 0.4445 270)
			(size 0.1397 0.1397)
			(layers "B.Cu" "B.Mask" "B.Paste")
			(net "BMC_IOEXP_SDA_10")
			(options
				(clearance outline)
				(anchor circle)
			)
			(primitives
				(gr_poly
					(pts
						(arc
							(start -0.1778 0.2794)
							(mid -0.249642 0.249642)
							(end -0.2794 0.1778)
						)
						(arc
							(start -0.2794 -0.1778)
							(mid -0.249642 -0.249642)
							(end -0.1778 -0.2794)
						)
						(arc
							(start 0.1778 -0.2794)
							(mid 0.249642 -0.249642)
							(end 0.2794 -0.1778)
						)
						(arc
							(start 0.2794 0.1778)
							(mid 0.249642 0.249642)
							(end 0.1778 0.2794)
						)
					)
					(width 0)
					(fill yes)
				)
			)
		)
	)
	(footprint ""
		(layer "B.Cu")
		(at 122.56897 -96.393 180)
		(property "Reference" "SC1187"
			(at 0 0 0)
			(layer "B.SilkS")
			(hide yes)
			(effects
				(font
					(size 1.27 1.27)
				)
				(justify mirror)
			)
		)
		(property "Value" "SCD1U6D3V1KX-GP"
			(at 2.8321 -1.7399 180)
			(unlocked yes)
			(layer "B.Fab")
			(hide yes)
			(effects
				(font
					(size 1.016 1.016)
					(thickness 0.1524)
				)
				(justify mirror)
			)
		)
		(property "Device Type" "C0201H13"
			(at 2.8321 -3.2639 180)
			(unlocked yes)
			(layer "B.Fab")
			(hide yes)
			(effects
				(font
					(size 1.016 1.016)
					(thickness 0.1524)
				)
				(justify mirror)
			)
		)
		(duplicate_pad_numbers_are_jumpers no)
		(fp_rect
			(start 0.2794 0.6477)
			(end -0.2794 -0.6477)
			(stroke
				(width 0)
				(type default)
			)
			(fill no)
			(layer "B.CrtYd")
		)
		(fp_rect
			(start 0.2794 0.6477)
			(end -0.2794 -0.6477)
			(stroke
				(width 0)
				(type default)
			)
			(fill no)
			(layer "B.Fab")
		)
		(pad "1" smd custom
			(at 0 -0.2794)
			(size 0.0762 0.0762)
			(layers "B.Cu" "B.Mask" "B.Paste")
			(net "GB_VDDA")
			(options
				(clearance outline)
				(anchor circle)
			)
			(primitives
				(gr_poly
					(pts
						(arc
							(start 0.1524 0.127)
							(mid 0.137521 0.162921)
							(end 0.1016 0.1778)
						)
						(arc
							(start -0.1016 0.1778)
							(mid -0.137521 0.162921)
							(end -0.1524 0.127)
						)
						(arc
							(start -0.1524 -0.127)
							(mid -0.137521 -0.162921)
							(end -0.1016 -0.1778)
						)
						(arc
							(start 0.1016 -0.1778)
							(mid 0.137521 -0.162921)
							(end 0.1524 -0.127)
						)
					)
					(width 0)
					(fill yes)
				)
			)
		)
		(pad "2" smd custom
			(at 0 0.2794)
			(size 0.0762 0.0762)
			(layers "B.Cu" "B.Mask" "B.Paste")
			(net "GND")
			(options
				(clearance outline)
				(anchor circle)
			)
			(primitives
				(gr_poly
					(pts
						(arc
							(start 0.1524 0.127)
							(mid 0.137521 0.162921)
							(end 0.1016 0.1778)
						)
						(arc
							(start -0.1016 0.1778)
							(mid -0.137521 0.162921)
							(end -0.1524 0.127)
						)
						(arc
							(start -0.1524 -0.127)
							(mid -0.137521 -0.162921)
							(end -0.1016 -0.1778)
						)
						(arc
							(start 0.1016 -0.1778)
							(mid 0.137521 -0.162921)
							(end 0.1524 -0.127)
						)
					)
					(width 0)
					(fill yes)
				)
			)
		)
	)
	(footprint ""
		(layer "B.Cu")
		(at 109.544612 -221.996)
		(property "Reference" "SR896"
			(at 0 0 0)
			(layer "B.SilkS")
			(hide yes)
			(effects
				(font
					(size 1.27 1.27)
				)
				(justify mirror)
			)
		)
		(property "Value" "0R2J-2-GP"
			(at -0.064008 -3.993896 0)
			(unlocked yes)
			(layer "B.Fab")
			(hide yes)
			(effects
				(font
					(size 1.016 1.016)
					(thickness 0.1524)
				)
				(justify mirror)
			)
		)
		(property "Device Type" "R402H16"
			(at -0.064008 -5.517896 0)
			(unlocked yes)
			(layer "B.Fab")
			(hide yes)
			(effects
				(font
					(size 1.016 1.016)
					(thickness 0.1524)
				)
				(justify mirror)
			)
		)
		(duplicate_pad_numbers_are_jumpers no)
		(fp_line
			(start -0.508 -0.9398)
			(end 0.508 -0.9398)
			(stroke
				(width 0.1524)
				(type default)
			)
			(layer "B.SilkS")
		)
		(fp_line
			(start 0.508 -0.9398)
			(end 0.508 0.9398)
			(stroke
				(width 0.1524)
				(type default)
			)
			(layer "B.SilkS")
		)
		(fp_rect
			(start 0.508 0.9398)
			(end -0.508 -0.9398)
			(stroke
				(width 0)
				(type default)
			)
			(fill no)
			(layer "B.CrtYd")
		)
		(fp_rect
			(start 0.508 0.9398)
			(end -0.508 -0.9398)
			(stroke
				(width 0)
				(type default)
			)
			(fill no)
			(layer "B.Fab")
		)
		(pad "1" smd custom
			(at 0 -0.4445 180)
			(size 0.1397 0.1397)
			(layers "B.Cu" "B.Mask" "B.Paste")
			(net "SAS_GF_EXP_RX_DN8")
			(options
				(clearance outline)
				(anchor circle)
			)
			(primitives
				(gr_poly
					(pts
						(arc
							(start -0.1778 0.2794)
							(mid -0.249642 0.249642)
							(end -0.2794 0.1778)
						)
						(arc
							(start -0.2794 -0.1778)
							(mid -0.249642 -0.249642)
							(end -0.1778 -0.2794)
						)
						(arc
							(start 0.1778 -0.2794)
							(mid 0.249642 -0.249642)
							(end 0.2794 -0.1778)
						)
						(arc
							(start 0.2794 0.1778)
							(mid 0.249642 0.249642)
							(end 0.1778 0.2794)
						)
					)
					(width 0)
					(fill yes)
				)
			)
		)
		(pad "2" smd custom
			(at 0 0.4445 180)
			(size 0.1397 0.1397)
			(layers "B.Cu" "B.Mask" "B.Paste")
			(net "SAS_HDD_CONN_SER_RX8_N")
			(options
				(clearance outline)
				(anchor circle)
			)
			(primitives
				(gr_poly
					(pts
						(arc
							(start -0.1778 0.2794)
							(mid -0.249642 0.249642)
							(end -0.2794 0.1778)
						)
						(arc
							(start -0.2794 -0.1778)
							(mid -0.249642 -0.249642)
							(end -0.1778 -0.2794)
						)
						(arc
							(start 0.1778 -0.2794)
							(mid 0.249642 -0.249642)
							(end 0.2794 -0.1778)
						)
						(arc
							(start 0.2794 0.1778)
							(mid 0.249642 0.249642)
							(end 0.1778 0.2794)
						)
					)
					(width 0)
					(fill yes)
				)
			)
		)
	)
	(footprint ""
		(layer "B.Cu")
		(at 81.153 -18.796 180)
		(property "Reference" "PC212"
			(at 0 0 0)
			(layer "B.SilkS")
			(hide yes)
			(effects
				(font
					(size 1.27 1.27)
				)
				(justify mirror)
			)
		)
		(property "Value" "SC1U25V3KX-GP"
			(at 0 -2.8194 180)
			(unlocked yes)
			(layer "B.Fab")
			(hide yes)
			(effects
				(font
					(size 1.016 1.016)
					(thickness 0.1524)
				)
				(justify mirror)
			)
		)
		(property "Device Type" "C603H36"
			(at 0 -4.3434 180)
			(unlocked yes)
			(layer "B.Fab")
			(hide yes)
			(effects
				(font
					(size 1.016 1.016)
					(thickness 0.1524)
				)
				(justify mirror)
			)
		)
		(duplicate_pad_numbers_are_jumpers no)
		(fp_line
			(start -0.508 0)
			(end 0.508 0)
			(stroke
				(width 0.2032)
				(type default)
			)
			(layer "B.SilkS")
		)
		(fp_rect
			(start 0.5842 1.3335)
			(end -0.5842 -1.3335)
			(stroke
				(width 0)
				(type default)
			)
			(fill no)
			(layer "B.CrtYd")
		)
		(fp_rect
			(start 0.5842 1.3335)
			(end -0.5842 -1.3335)
			(stroke
				(width 0)
				(type default)
			)
			(fill no)
			(layer "B.Fab")
		)
		(pad "1" smd custom
			(at 0 -0.762)
			(size 0.2159 0.2159)
			(layers "B.Cu" "B.Mask" "B.Paste")
			(net "VT235_AVDD")
			(options
				(clearance outline)
				(anchor circle)
			)
			(primitives
				(gr_poly
					(pts
						(arc
							(start -0.3302 0.4318)
							(mid -0.402042 0.402042)
							(end -0.4318 0.3302)
						)
						(arc
							(start -0.4318 -0.3302)
							(mid -0.402042 -0.402042)
							(end -0.3302 -0.4318)
						)
						(arc
							(start 0.3302 -0.4318)
							(mid 0.402042 -0.402042)
							(end 0.4318 -0.3302)
						)
						(arc
							(start 0.4318 0.3302)
							(mid 0.402042 0.402042)
							(end 0.3302 0.4318)
						)
					)
					(width 0)
					(fill yes)
				)
			)
		)
		(pad "2" smd custom
			(at 0 0.762)
			(size 0.2159 0.2159)
			(layers "B.Cu" "B.Mask" "B.Paste")
			(net "AGND_P0V9_C")
			(options
				(clearance outline)
				(anchor circle)
			)
			(primitives
				(gr_poly
					(pts
						(arc
							(start -0.3302 0.4318)
							(mid -0.402042 0.402042)
							(end -0.4318 0.3302)
						)
						(arc
							(start -0.4318 -0.3302)
							(mid -0.402042 -0.402042)
							(end -0.3302 -0.4318)
						)
						(arc
							(start 0.3302 -0.4318)
							(mid 0.402042 -0.402042)
							(end 0.4318 -0.3302)
						)
						(arc
							(start 0.4318 0.3302)
							(mid 0.402042 0.402042)
							(end 0.3302 0.4318)
						)
					)
					(width 0)
					(fill yes)
				)
			)
		)
	)
	(footprint ""
		(layer "B.Cu")
		(at 101.854 -239.395)
		(property "Reference" "SR845"
			(at 0 0 0)
			(layer "B.SilkS")
			(hide yes)
			(effects
				(font
					(size 1.27 1.27)
				)
				(justify mirror)
			)
		)
		(property "Value" "4K7R2F-GP"
			(at -0.064008 -3.993896 0)
			(unlocked yes)
			(layer "B.Fab")
			(hide yes)
			(effects
				(font
					(size 1.016 1.016)
					(thickness 0.1524)
				)
				(justify mirror)
			)
		)
		(property "Device Type" "R402H16"
			(at -0.064008 -5.517896 0)
			(unlocked yes)
			(layer "B.Fab")
			(hide yes)
			(effects
				(font
					(size 1.016 1.016)
					(thickness 0.1524)
				)
				(justify mirror)
			)
		)
		(duplicate_pad_numbers_are_jumpers no)
		(fp_line
			(start -0.508 -0.9398)
			(end 0.508 -0.9398)
			(stroke
				(width 0.1524)
				(type default)
			)
			(layer "B.SilkS")
		)
		(fp_line
			(start 0.508 -0.9398)
			(end 0.508 0.9398)
			(stroke
				(width 0.1524)
				(type default)
			)
			(layer "B.SilkS")
		)
		(fp_rect
			(start 0.508 0.9398)
			(end -0.508 -0.9398)
			(stroke
				(width 0)
				(type default)
			)
			(fill no)
			(layer "B.CrtYd")
		)
		(fp_rect
			(start 0.508 0.9398)
			(end -0.508 -0.9398)
			(stroke
				(width 0)
				(type default)
			)
			(fill no)
			(layer "B.Fab")
		)
		(pad "1" smd custom
			(at 0 -0.4445 180)
			(size 0.1397 0.1397)
			(layers "B.Cu" "B.Mask" "B.Paste")
			(net "SAS_FAULT_LED2")
			(options
				(clearance outline)
				(anchor circle)
			)
			(primitives
				(gr_poly
					(pts
						(arc
							(start -0.1778 0.2794)
							(mid -0.249642 0.249642)
							(end -0.2794 0.1778)
						)
						(arc
							(start -0.2794 -0.1778)
							(mid -0.249642 -0.249642)
							(end -0.1778 -0.2794)
						)
						(arc
							(start 0.1778 -0.2794)
							(mid 0.249642 -0.249642)
							(end 0.2794 -0.1778)
						)
						(arc
							(start 0.2794 0.1778)
							(mid 0.249642 0.249642)
							(end 0.1778 0.2794)
						)
					)
					(width 0)
					(fill yes)
				)
			)
		)
		(pad "2" smd custom
			(at 0 0.4445 180)
			(size 0.1397 0.1397)
			(layers "B.Cu" "B.Mask" "B.Paste")
			(net "P3V3_STBY")
			(options
				(clearance outline)
				(anchor circle)
			)
			(primitives
				(gr_poly
					(pts
						(arc
							(start -0.1778 0.2794)
							(mid -0.249642 0.249642)
							(end -0.2794 0.1778)
						)
						(arc
							(start -0.2794 -0.1778)
							(mid -0.249642 -0.249642)
							(end -0.1778 -0.2794)
						)
						(arc
							(start 0.1778 -0.2794)
							(mid 0.249642 -0.249642)
							(end 0.2794 -0.1778)
						)
						(arc
							(start 0.2794 0.1778)
							(mid 0.249642 0.249642)
							(end 0.1778 0.2794)
						)
					)
					(width 0)
					(fill yes)
				)
			)
		)
	)
	(footprint ""
		(layer "B.Cu")
		(at 114.82197 -86.868 -90)
		(property "Reference" "SC1234"
			(at 0 0 90)
			(layer "B.SilkS")
			(hide yes)
			(effects
				(font
					(size 1.27 1.27)
				)
				(justify mirror)
			)
		)
		(property "Value" "SCD1U6D3V1KX-GP"
			(at 2.8321 -1.7399 270)
			(unlocked yes)
			(layer "B.Fab")
			(hide yes)
			(effects
				(font
					(size 1.016 1.016)
					(thickness 0.1524)
				)
				(justify mirror)
			)
		)
		(property "Device Type" "C0201H13"
			(at 2.8321 -3.2639 270)
			(unlocked yes)
			(layer "B.Fab")
			(hide yes)
			(effects
				(font
					(size 1.016 1.016)
					(thickness 0.1524)
				)
				(justify mirror)
			)
		)
		(duplicate_pad_numbers_are_jumpers no)
		(fp_rect
			(start 0.2794 0.6477)
			(end -0.2794 -0.6477)
			(stroke
				(width 0)
				(type default)
			)
			(fill no)
			(layer "B.CrtYd")
		)
		(fp_rect
			(start 0.2794 0.6477)
			(end -0.2794 -0.6477)
			(stroke
				(width 0)
				(type default)
			)
			(fill no)
			(layer "B.Fab")
		)
		(pad "1" smd custom
			(at 0 -0.2794 90)
			(size 0.0762 0.0762)
			(layers "B.Cu" "B.Mask" "B.Paste")
			(net "P1V8_E")
			(options
				(clearance outline)
				(anchor circle)
			)
			(primitives
				(gr_poly
					(pts
						(arc
							(start 0.1524 0.127)
							(mid 0.137521 0.162921)
							(end 0.1016 0.1778)
						)
						(arc
							(start -0.1016 0.1778)
							(mid -0.137521 0.162921)
							(end -0.1524 0.127)
						)
						(arc
							(start -0.1524 -0.127)
							(mid -0.137521 -0.162921)
							(end -0.1016 -0.1778)
						)
						(arc
							(start 0.1016 -0.1778)
							(mid 0.137521 -0.162921)
							(end 0.1524 -0.127)
						)
					)
					(width 0)
					(fill yes)
				)
			)
		)
		(pad "2" smd custom
			(at 0 0.2794 90)
			(size 0.0762 0.0762)
			(layers "B.Cu" "B.Mask" "B.Paste")
			(net "GND")
			(options
				(clearance outline)
				(anchor circle)
			)
			(primitives
				(gr_poly
					(pts
						(arc
							(start 0.1524 0.127)
							(mid 0.137521 0.162921)
							(end 0.1016 0.1778)
						)
						(arc
							(start -0.1016 0.1778)
							(mid -0.137521 0.162921)
							(end -0.1524 0.127)
						)
						(arc
							(start -0.1524 -0.127)
							(mid -0.137521 -0.162921)
							(end -0.1016 -0.1778)
						)
						(arc
							(start 0.1016 -0.1778)
							(mid 0.137521 -0.162921)
							(end 0.1524 -0.127)
						)
					)
					(width 0)
					(fill yes)
				)
			)
		)
	)
	(footprint ""
		(layer "B.Cu")
		(at 110.30077 -88.6206 90)
		(property "Reference" "SC1225"
			(at 0 0 90)
			(layer "B.SilkS")
			(hide yes)
			(effects
				(font
					(size 1.27 1.27)
				)
				(justify mirror)
			)
		)
		(property "Value" "SCD1U6D3V1KX-GP"
			(at 2.8321 -1.7399 90)
			(unlocked yes)
			(layer "B.Fab")
			(hide yes)
			(effects
				(font
					(size 1.016 1.016)
					(thickness 0.1524)
				)
				(justify mirror)
			)
		)
		(property "Device Type" "C0201H13"
			(at 2.8321 -3.2639 90)
			(unlocked yes)
			(layer "B.Fab")
			(hide yes)
			(effects
				(font
					(size 1.016 1.016)
					(thickness 0.1524)
				)
				(justify mirror)
			)
		)
		(duplicate_pad_numbers_are_jumpers no)
		(fp_rect
			(start 0.2794 0.6477)
			(end -0.2794 -0.6477)
			(stroke
				(width 0)
				(type default)
			)
			(fill no)
			(layer "B.CrtYd")
		)
		(fp_rect
			(start 0.2794 0.6477)
			(end -0.2794 -0.6477)
			(stroke
				(width 0)
				(type default)
			)
			(fill no)
			(layer "B.Fab")
		)
		(pad "1" smd custom
			(at 0 -0.2794 270)
			(size 0.0762 0.0762)
			(layers "B.Cu" "B.Mask" "B.Paste")
			(net "P1V8_E")
			(options
				(clearance outline)
				(anchor circle)
			)
			(primitives
				(gr_poly
					(pts
						(arc
							(start 0.1524 0.127)
							(mid 0.137521 0.162921)
							(end 0.1016 0.1778)
						)
						(arc
							(start -0.1016 0.1778)
							(mid -0.137521 0.162921)
							(end -0.1524 0.127)
						)
						(arc
							(start -0.1524 -0.127)
							(mid -0.137521 -0.162921)
							(end -0.1016 -0.1778)
						)
						(arc
							(start 0.1016 -0.1778)
							(mid 0.137521 -0.162921)
							(end 0.1524 -0.127)
						)
					)
					(width 0)
					(fill yes)
				)
			)
		)
		(pad "2" smd custom
			(at 0 0.2794 270)
			(size 0.0762 0.0762)
			(layers "B.Cu" "B.Mask" "B.Paste")
			(net "GND")
			(options
				(clearance outline)
				(anchor circle)
			)
			(primitives
				(gr_poly
					(pts
						(arc
							(start 0.1524 0.127)
							(mid 0.137521 0.162921)
							(end 0.1016 0.1778)
						)
						(arc
							(start -0.1016 0.1778)
							(mid -0.137521 0.162921)
							(end -0.1524 0.127)
						)
						(arc
							(start -0.1524 -0.127)
							(mid -0.137521 -0.162921)
							(end -0.1016 -0.1778)
						)
						(arc
							(start 0.1016 -0.1778)
							(mid 0.137521 -0.162921)
							(end 0.1524 -0.127)
						)
					)
					(width 0)
					(fill yes)
				)
			)
		)
	)
)
